FILE_TYPE = MACRO_DRAWING;
SET COLOR_WIRE YELLOW;
SET COLOR_PROP MONO;
SET COLOR_DOT WHITE;
SET COLOR_ARC YELLOW;
SET COLOR_BODY GREEN;
SET COLOR_NOTE MONO;
SET PROP_DISPLAY VALUE;
SET PAGE_NUMBER P257;
FORCEADD INTEL_CORP_BPAGE..1
(-1350 1750);
FORCEPROP 1 LAST CDS_CON_LAST_MODIFIED Fri Jun 16 17:49:36 2017
J 0
(-2775 2075);
PAINT ORANGE (-2775 2075);
DISPLAY INVISIBLE (-2775 2075);
FORCEPROP 2 LAST CUSTOM_TXT_CDS <XR_PAGE_TITLE>
J 0
(-9240 7000);
DISPLAY 0.638298 (-9240 7000);
PAINT PINK (-9240 7000);
DISPLAY INVISIBLE (-9240 7000);
FORCEPROP 2 LAST CUSTOM_TXT_CDS <CURRENT_DESIGN_SHEET> OF <TOTAL_DESIGN_SHEETS>
J 0
(-1825 1775);
PAINT ORANGE (-1825 1775);
FORCEPROP 2 LAST CUSTOM_TXT_CDS <CON_LAST_MODIFIED>
J 0
(-5350 1850);
PAINT ORANGE (-5350 1850);
FORCEPROP 1 LAST SCH_TITLE SPI BLOCK DIAGRAM 1 OF 2
J 0
(-9300 1800);
DISPLAY 2.468085 (-9300 1800);
PAINT ORANGE (-9300 1800);
FORCEPROP 2 LAST PAGE_BORDER TRUE
J 0
(-9240 7000);
DISPLAY 0.638298 (-9240 7000);
PAINT PINK (-9240 7000);
DISPLAY INVISIBLE (-9240 7000);
FORCEPROP 2 LAST CDS_LIB mstr_symbols
J 0
(-1350 1750);
PAINT MONO (-1350 1750);
DISPLAY INVISIBLE (-1350 1750);
FORCEPROP 1 LAST COMMENT_BODY TRUE
J 0
(-1338 1762);
DISPLAY 0.468085 (-1338 1762);
PAINT GREEN (-1338 1762);
DISPLAY INVISIBLE (-1338 1762);
FORCEPROP 2 LAST CDS_XR_PAGE_TITLE CR-262 : @BASEBOARD_FAB2_LIB.BASEBOARD_FAB2(SCH_1):PAGE262
J 0
(-9240 7000);
DISPLAY 0.638298 (-9240 7000);
PAINT PINK (-9240 7000);
DISPLAY INVISIBLE (-9240 7000);
FORCENOTE
$CDS_IMAGE|SPI Block diagram_1_0406_J.jpg|6332|4750
(-5250 4425) 0;
DISPLAY LEFT (-5250 4425);
QUIT
